# T6G (Grand Teton) — schematic netlist excerpt (pin names and nets, part order shuffled) for the footprints in the layout excerpt that follows; sources: Cadence DE-HDL packaged netlist, KiCad conversion of 04192023_DAF0TMB3IC0_F0TG_MB_C_brd_V02_OCP.brd

PC626_3  Q_CAP  22UF 16V 20% X6S  pkg C0805  page 223 : A = SW_P12V_AUX_PVDDIO_P1_FLT ; B = GND
PR212  Q_RES  0 5% CHIP  pkg 0402LF  page 215 : A = PVDDCR_SOC_P1_VOS2 ; B = PVDDCR_SOC_P1
C2298  Q_CAP  22UF 4V 20% X6S  pkg C0402  page 73 : A = PVDDCR_CPU0_P1 ; B = GND

(kicad_pcb
	(version 20260206)
	(generator "pcbnew")
	(generator_version "10.0")
	(general
		(thickness 1.6)
		(legacy_teardrops no)
	)
	(paper "A4")
	(title_block
		(title "04192023_DAF0TMB3IC0_F0TG_MB_C_brd_V02_OCP.brd")
		(comment 1 "Grand Teton / footprints 6051-6053 of 8354")
	)
	(layers
		(0 "F.Cu" signal "TOP")
		(4 "In1.Cu" signal "GND")
		(6 "In2.Cu" signal "IN1")
		(8 "In3.Cu" signal "GND1")
		(10 "In4.Cu" signal "IN2")
		(12 "In5.Cu" signal "GND2")
		(14 "In6.Cu" signal "IN3")
		(16 "In7.Cu" signal "GND3")
		(18 "In8.Cu" signal "VCC")
		(20 "In9.Cu" signal "VCC1")
		(22 "In10.Cu" signal "GND4")
		(24 "In11.Cu" signal "IN4")
		(26 "In12.Cu" signal "GND5")
		(28 "In13.Cu" signal "IN5")
		(30 "In14.Cu" signal "GND6")
		(32 "In15.Cu" signal "IN6")
		(34 "In16.Cu" signal "GND7")
		(2 "B.Cu" signal "BOTTOM")
		(9 "F.Adhes" user "F.Adhesive")
		(11 "B.Adhes" user "B.Adhesive")
		(13 "F.Paste" user "Package Geometry/Pastemask Top")
		(15 "B.Paste" user "Package Geometry/Pastemask Bottom")
		(5 "F.SilkS" user "Ref Des/Silkscreen Top")
		(7 "B.SilkS" user "Ref Des/Silkscreen Bottom")
		(1 "F.Mask" user "Board Geometry/Soldermask Top")
		(3 "B.Mask" user "Board Geometry/Soldermask Bottom")
		(17 "Dwgs.User" user "User.Drawings")
		(19 "Cmts.User" user "User.Comments")
		(21 "Eco1.User" user "User.Eco1")
		(23 "Eco2.User" user "User.Eco2")
		(25 "Edge.Cuts" user "Board Geometry/Outline")
		(27 "Margin" user)
		(31 "F.CrtYd" user "Package Geometry/Place Bound Top")
		(29 "B.CrtYd" user "Package Geometry/Place Bound Bottom")
		(35 "F.Fab" user "Ref Des/Assembly Top")
		(33 "B.Fab" user "Ref Des/Assembly Bottom")
	)
	(footprint ""
		(layer "B.Cu")
		(at 108.526834 -249.368564 180)
		(property "Reference" "C2298"
			(at 0 0 0)
			(layer "B.SilkS")
			(hide yes)
			(effects
				(font
					(size 1.27 1.27)
				)
				(justify mirror)
			)
		)
		(property "Value" ""
			(at 0 0 0)
			(layer "B.Fab")
			(effects
				(font
					(size 1.27 1.27)
				)
				(justify mirror)
			)
		)
		(duplicate_pad_numbers_are_jumpers no)
		(fp_line
			(start 0.7874 0.4064)
			(end 0.7874 -0.4064)
			(stroke
				(width 0.1524)
				(type default)
			)
			(layer "B.SilkS")
		)
		(fp_line
			(start 0.7874 -0.4064)
			(end -0.7874 -0.4064)
			(stroke
				(width 0.1524)
				(type default)
			)
			(layer "B.SilkS")
		)
		(fp_line
			(start -0.7874 0.4064)
			(end 0.7874 0.4064)
			(stroke
				(width 0.1524)
				(type default)
			)
			(layer "B.SilkS")
		)
		(fp_line
			(start -0.7874 -0.4064)
			(end -0.7874 0.4064)
			(stroke
				(width 0.1524)
				(type default)
			)
			(layer "B.SilkS")
		)
		(fp_line
			(start 0.67945 0.3048)
			(end 0.67945 -0.305054)
			(stroke
				(width 0.1)
				(type default)
			)
			(layer "B.Fab")
		)
		(fp_line
			(start 0.67945 -0.305054)
			(end 0.12065 -0.305054)
			(stroke
				(width 0.1)
				(type default)
			)
			(layer "B.Fab")
		)
		(fp_line
			(start 0.12065 0.3048)
			(end 0.67945 0.3048)
			(stroke
				(width 0.1)
				(type default)
			)
			(layer "B.Fab")
		)
		(fp_line
			(start 0.12065 0.2794)
			(end 0.12065 0.3048)
			(stroke
				(width 0.1)
				(type default)
			)
			(layer "B.Fab")
		)
		(fp_line
			(start 0.12065 -0.2794)
			(end -0.12065 -0.2794)
			(stroke
				(width 0.1)
				(type default)
			)
			(layer "B.Fab")
		)
		(fp_line
			(start 0.12065 -0.305054)
			(end 0.12065 -0.2794)
			(stroke
				(width 0.1)
				(type default)
			)
			(layer "B.Fab")
		)
		(fp_line
			(start -0.120396 0.3048)
			(end -0.120396 0.2794)
			(stroke
				(width 0.1)
				(type default)
			)
			(layer "B.Fab")
		)
		(fp_line
			(start -0.120396 0.2794)
			(end 0.12065 0.2794)
			(stroke
				(width 0.1)
				(type default)
			)
			(layer "B.Fab")
		)
		(fp_line
			(start -0.12065 -0.2794)
			(end -0.12065 -0.3048)
			(stroke
				(width 0.1)
				(type default)
			)
			(layer "B.Fab")
		)
		(fp_line
			(start -0.12065 -0.3048)
			(end -0.67945 -0.3048)
			(stroke
				(width 0.1)
				(type default)
			)
			(layer "B.Fab")
		)
		(fp_line
			(start -0.67945 0.3048)
			(end -0.120396 0.3048)
			(stroke
				(width 0.1)
				(type default)
			)
			(layer "B.Fab")
		)
		(fp_line
			(start -0.67945 -0.3048)
			(end -0.67945 0.3048)
			(stroke
				(width 0.1)
				(type default)
			)
			(layer "B.Fab")
		)
		(pad "1" smd circle
			(at 0.40005 0)
			(size 0 0)
			(layers "B.Cu" "B.Mask" "B.Paste")
			(net "PVDDCR_CPU0_P1")
		)
		(pad "2" smd circle
			(at -0.40005 0)
			(size 0 0)
			(layers "B.Cu" "B.Mask" "B.Paste")
			(net "GND")
		)
	)
	(footprint ""
		(layer "B.Cu")
		(at 38.002718 -346.788994 90)
		(property "Reference" "PC626_3"
			(at 0 0 90)
			(layer "B.SilkS")
			(hide yes)
			(effects
				(font
					(size 1.27 1.27)
				)
				(justify mirror)
			)
		)
		(property "Value" ""
			(at 0 0 90)
			(layer "B.Fab")
			(effects
				(font
					(size 1.27 1.27)
				)
				(justify mirror)
			)
		)
		(duplicate_pad_numbers_are_jumpers no)
		(fp_line
			(start 1.524 -0.762)
			(end -1.524 -0.762)
			(stroke
				(width 0.1524)
				(type default)
			)
			(layer "B.SilkS")
		)
		(fp_line
			(start -1.524 -0.762)
			(end -1.524 0.762)
			(stroke
				(width 0.1524)
				(type default)
			)
			(layer "B.SilkS")
		)
		(fp_line
			(start 1.524 0.762)
			(end 1.524 -0.762)
			(stroke
				(width 0.1524)
				(type default)
			)
			(layer "B.SilkS")
		)
		(fp_line
			(start -1.524 0.762)
			(end 1.524 0.762)
			(stroke
				(width 0.1524)
				(type default)
			)
			(layer "B.SilkS")
		)
		(fp_line
			(start 1.1049 -0.724916)
			(end 1.1049 0.724916)
			(stroke
				(width 0.1)
				(type default)
			)
			(layer "B.Fab")
		)
		(fp_line
			(start -1.1049 -0.724916)
			(end 1.1049 -0.724916)
			(stroke
				(width 0.1)
				(type default)
			)
			(layer "B.Fab")
		)
		(fp_line
			(start 1.1049 0.724916)
			(end -1.1049 0.724916)
			(stroke
				(width 0.1)
				(type default)
			)
			(layer "B.Fab")
		)
		(fp_line
			(start -1.1049 0.724916)
			(end -1.1049 -0.724916)
			(stroke
				(width 0.1)
				(type default)
			)
			(layer "B.Fab")
		)
		(pad "1" smd rect
			(at 0.889 0 90)
			(size 1.016 1.27)
			(layers "B.Cu" "B.Mask" "B.Paste")
			(net "SW_P12V_AUX_PVDDIO_P1_FLT")
		)
		(pad "2" smd rect
			(at -0.889 0 90)
			(size 1.016 1.27)
			(layers "B.Cu" "B.Mask" "B.Paste")
			(net "GND")
		)
	)
	(footprint ""
		(layer "B.Cu")
		(at 127.62738 -162.527234 90)
		(property "Reference" "PR212"
			(at 0 0 90)
			(layer "B.SilkS")
			(hide yes)
			(effects
				(font
					(size 1.27 1.27)
				)
				(justify mirror)
			)
		)
		(property "Value" ""
			(at 0 0 90)
			(layer "B.Fab")
			(effects
				(font
					(size 1.27 1.27)
				)
				(justify mirror)
			)
		)
		(duplicate_pad_numbers_are_jumpers no)
		(fp_line
			(start 0.7874 -0.4064)
			(end -0.7874 -0.4064)
			(stroke
				(width 0.1524)
				(type default)
			)
			(layer "B.SilkS")
		)
		(fp_line
			(start -0.7874 -0.4064)
			(end -0.7874 0.4064)
			(stroke
				(width 0.1524)
				(type default)
			)
			(layer "B.SilkS")
		)
		(fp_line
			(start 0.7874 0.4064)
			(end 0.7874 -0.4064)
			(stroke
				(width 0.1524)
				(type default)
			)
			(layer "B.SilkS")
		)
		(fp_line
			(start -0.7874 0.4064)
			(end 0.7874 0.4064)
			(stroke
				(width 0.1524)
				(type default)
			)
			(layer "B.SilkS")
		)
		(fp_line
			(start 0.67945 -0.305054)
			(end 0.12065 -0.305054)
			(stroke
				(width 0.1)
				(type default)
			)
			(layer "B.Fab")
		)
		(fp_line
			(start 0.12065 -0.305054)
			(end 0.12065 -0.2794)
			(stroke
				(width 0.1)
				(type default)
			)
			(layer "B.Fab")
		)
		(fp_line
			(start -0.12065 -0.3048)
			(end -0.67945 -0.3048)
			(stroke
				(width 0.1)
				(type default)
			)
			(layer "B.Fab")
		)
		(fp_line
			(start -0.67945 -0.3048)
			(end -0.67945 0.3048)
			(stroke
				(width 0.1)
				(type default)
			)
			(layer "B.Fab")
		)
		(fp_line
			(start 0.12065 -0.2794)
			(end -0.12065 -0.2794)
			(stroke
				(width 0.1)
				(type default)
			)
			(layer "B.Fab")
		)
		(fp_line
			(start -0.12065 -0.2794)
			(end -0.12065 -0.3048)
			(stroke
				(width 0.1)
				(type default)
			)
			(layer "B.Fab")
		)
		(fp_line
			(start 0.12065 0.2794)
			(end 0.12065 0.3048)
			(stroke
				(width 0.1)
				(type default)
			)
			(layer "B.Fab")
		)
		(fp_line
			(start -0.120396 0.2794)
			(end 0.12065 0.2794)
			(stroke
				(width 0.1)
				(type default)
			)
			(layer "B.Fab")
		)
		(fp_line
			(start 0.67945 0.3048)
			(end 0.67945 -0.305054)
			(stroke
				(width 0.1)
				(type default)
			)
			(layer "B.Fab")
		)
		(fp_line
			(start 0.12065 0.3048)
			(end 0.67945 0.3048)
			(stroke
				(width 0.1)
				(type default)
			)
			(layer "B.Fab")
		)
		(fp_line
			(start -0.120396 0.3048)
			(end -0.120396 0.2794)
			(stroke
				(width 0.1)
				(type default)
			)
			(layer "B.Fab")
		)
		(fp_line
			(start -0.67945 0.3048)
			(end -0.120396 0.3048)
			(stroke
				(width 0.1)
				(type default)
			)
			(layer "B.Fab")
		)
		(pad "1" smd circle
			(at 0.40005 0 270)
			(size 0 0)
			(layers "B.Cu" "B.Mask" "B.Paste")
			(net "PVDDCR_SOC_P1_VOS2")
		)
		(pad "2" smd circle
			(at -0.40005 0 270)
			(size 0 0)
			(layers "B.Cu" "B.Mask" "B.Paste")
			(net "PVDDCR_SOC_P1")
		)
	)
)
